# S9S_MB_2U (Grand Teton) — schematic netlist excerpt (pin names and nets, part order shuffled) for the footprints in the layout excerpt that follows; sources: Cadence DE-HDL packaged netlist, KiCad conversion of 03242023_DA0F0TMBIJ0_F0T_Motherboard_J_brd_V01_OCP.brd

PC490_P1_7  Q_CAP  22UF 16V 20% X6S  pkg C0805  page 288 : A = SW_P12V_PVCCIN_CPU1_FLT ; B = GND
R293  Q_RES  240 1% EMPTY  pkg 0402LF  page 119 : A = PD_CPU0_TXT_PLTEN ; B = GND

(kicad_pcb
	(version 20260206)
	(generator "pcbnew")
	(generator_version "10.0")
	(general
		(thickness 1.6)
		(legacy_teardrops no)
	)
	(paper "A4")
	(title_block
		(title "03242023_DA0F0TMBIJ0_F0T_Motherboard_J_brd_V01_OCP.brd")
		(comment 1 "Grand Teton / footprints 5081-5082 of 6105")
	)
	(layers
		(0 "F.Cu" signal "TOP")
		(4 "In1.Cu" signal "GND")
		(6 "In2.Cu" signal "IN1")
		(8 "In3.Cu" signal "GND1")
		(10 "In4.Cu" signal "IN2")
		(12 "In5.Cu" signal "GND2")
		(14 "In6.Cu" signal "IN3")
		(16 "In7.Cu" signal "GND3")
		(18 "In8.Cu" signal "VCC")
		(20 "In9.Cu" signal "VCC1")
		(22 "In10.Cu" signal "GND4")
		(24 "In11.Cu" signal "IN4")
		(26 "In12.Cu" signal "GND5")
		(28 "In13.Cu" signal "IN5")
		(30 "In14.Cu" signal "GND6")
		(32 "In15.Cu" signal "IN6")
		(34 "In16.Cu" signal "GND7")
		(2 "B.Cu" signal "BOTTOM")
		(9 "F.Adhes" user "F.Adhesive")
		(11 "B.Adhes" user "B.Adhesive")
		(13 "F.Paste" user "Package Geometry/Pastemask Top")
		(15 "B.Paste" user "Package Geometry/Pastemask Bottom")
		(5 "F.SilkS" user "Ref Des/Silkscreen Top")
		(7 "B.SilkS" user "Ref Des/Silkscreen Bottom")
		(1 "F.Mask" user "Board Geometry/Soldermask Top")
		(3 "B.Mask" user "Board Geometry/Soldermask Bottom")
		(17 "Dwgs.User" user "User.Drawings")
		(19 "Cmts.User" user "User.Comments")
		(21 "Eco1.User" user "User.Eco1")
		(23 "Eco2.User" user "User.Eco2")
		(25 "Edge.Cuts" user "Board Geometry/Outline")
		(27 "Margin" user)
		(31 "F.CrtYd" user "Package Geometry/Place Bound Top")
		(29 "B.CrtYd" user "Package Geometry/Place Bound Bottom")
		(35 "F.Fab" user "Ref Des/Assembly Top")
		(33 "B.Fab" user "Ref Des/Assembly Bottom")
	)
	(footprint ""
		(layer "B.Cu")
		(at 381.608584 -186.138058 90)
		(property "Reference" "R293"
			(at 0 0 90)
			(layer "B.SilkS")
			(hide yes)
			(effects
				(font
					(size 1.27 1.27)
				)
				(justify mirror)
			)
		)
		(property "Value" ""
			(at 0 0 90)
			(layer "B.Fab")
			(effects
				(font
					(size 1.27 1.27)
				)
				(justify mirror)
			)
		)
		(duplicate_pad_numbers_are_jumpers no)
		(fp_line
			(start 0.7874 -0.4064)
			(end -0.7874 -0.4064)
			(stroke
				(width 0.1524)
				(type default)
			)
			(layer "B.SilkS")
		)
		(fp_line
			(start -0.7874 -0.4064)
			(end -0.7874 0.4064)
			(stroke
				(width 0.1524)
				(type default)
			)
			(layer "B.SilkS")
		)
		(fp_line
			(start 0.7874 0.4064)
			(end 0.7874 -0.4064)
			(stroke
				(width 0.1524)
				(type default)
			)
			(layer "B.SilkS")
		)
		(fp_line
			(start -0.7874 0.4064)
			(end 0.7874 0.4064)
			(stroke
				(width 0.1524)
				(type default)
			)
			(layer "B.SilkS")
		)
		(fp_line
			(start 0.67945 -0.305054)
			(end 0.12065 -0.305054)
			(stroke
				(width 0.1)
				(type default)
			)
			(layer "B.Fab")
		)
		(fp_line
			(start 0.12065 -0.305054)
			(end 0.12065 -0.2794)
			(stroke
				(width 0.1)
				(type default)
			)
			(layer "B.Fab")
		)
		(fp_line
			(start -0.12065 -0.3048)
			(end -0.67945 -0.3048)
			(stroke
				(width 0.1)
				(type default)
			)
			(layer "B.Fab")
		)
		(fp_line
			(start -0.67945 -0.3048)
			(end -0.67945 0.3048)
			(stroke
				(width 0.1)
				(type default)
			)
			(layer "B.Fab")
		)
		(fp_line
			(start 0.12065 -0.2794)
			(end -0.12065 -0.2794)
			(stroke
				(width 0.1)
				(type default)
			)
			(layer "B.Fab")
		)
		(fp_line
			(start -0.12065 -0.2794)
			(end -0.12065 -0.3048)
			(stroke
				(width 0.1)
				(type default)
			)
			(layer "B.Fab")
		)
		(fp_line
			(start 0.12065 0.2794)
			(end 0.12065 0.3048)
			(stroke
				(width 0.1)
				(type default)
			)
			(layer "B.Fab")
		)
		(fp_line
			(start -0.120396 0.2794)
			(end 0.12065 0.2794)
			(stroke
				(width 0.1)
				(type default)
			)
			(layer "B.Fab")
		)
		(fp_line
			(start 0.67945 0.3048)
			(end 0.67945 -0.305054)
			(stroke
				(width 0.1)
				(type default)
			)
			(layer "B.Fab")
		)
		(fp_line
			(start 0.12065 0.3048)
			(end 0.67945 0.3048)
			(stroke
				(width 0.1)
				(type default)
			)
			(layer "B.Fab")
		)
		(fp_line
			(start -0.120396 0.3048)
			(end -0.120396 0.2794)
			(stroke
				(width 0.1)
				(type default)
			)
			(layer "B.Fab")
		)
		(fp_line
			(start -0.67945 0.3048)
			(end -0.120396 0.3048)
			(stroke
				(width 0.1)
				(type default)
			)
			(layer "B.Fab")
		)
		(pad "1" smd circle
			(at 0.40005 0 270)
			(size 0 0)
			(layers "B.Cu" "B.Mask" "B.Paste")
			(net "PD_CPU0_TXT_PLTEN")
		)
		(pad "2" smd circle
			(at -0.40005 0 270)
			(size 0 0)
			(layers "B.Cu" "B.Mask" "B.Paste")
			(net "GND")
		)
	)
	(footprint ""
		(layer "B.Cu")
		(at 82.180176 -346.808298 -90)
		(property "Reference" "PC490_P1_7"
			(at 0 0 90)
			(layer "B.SilkS")
			(hide yes)
			(effects
				(font
					(size 1.27 1.27)
				)
				(justify mirror)
			)
		)
		(property "Value" ""
			(at 0 0 90)
			(layer "B.Fab")
			(effects
				(font
					(size 1.27 1.27)
				)
				(justify mirror)
			)
		)
		(duplicate_pad_numbers_are_jumpers no)
		(fp_line
			(start -1.524 0.762)
			(end 1.524 0.762)
			(stroke
				(width 0.1524)
				(type default)
			)
			(layer "B.SilkS")
		)
		(fp_line
			(start 1.524 0.762)
			(end 1.524 -0.762)
			(stroke
				(width 0.1524)
				(type default)
			)
			(layer "B.SilkS")
		)
		(fp_line
			(start -1.524 -0.762)
			(end -1.524 0.762)
			(stroke
				(width 0.1524)
				(type default)
			)
			(layer "B.SilkS")
		)
		(fp_line
			(start 1.524 -0.762)
			(end -1.524 -0.762)
			(stroke
				(width 0.1524)
				(type default)
			)
			(layer "B.SilkS")
		)
		(fp_line
			(start -1.1049 0.724916)
			(end -1.1049 -0.724916)
			(stroke
				(width 0.1)
				(type default)
			)
			(layer "B.Fab")
		)
		(fp_line
			(start 1.1049 0.724916)
			(end -1.1049 0.724916)
			(stroke
				(width 0.1)
				(type default)
			)
			(layer "B.Fab")
		)
		(fp_line
			(start -1.1049 -0.724916)
			(end 1.1049 -0.724916)
			(stroke
				(width 0.1)
				(type default)
			)
			(layer "B.Fab")
		)
		(fp_line
			(start 1.1049 -0.724916)
			(end 1.1049 0.724916)
			(stroke
				(width 0.1)
				(type default)
			)
			(layer "B.Fab")
		)
		(pad "1" smd rect
			(at 0.889 0 270)
			(size 1.016 1.27)
			(layers "B.Cu" "B.Mask" "B.Paste")
			(net "SW_P12V_PVCCIN_CPU1_FLT")
		)
		(pad "2" smd rect
			(at -0.889 0 270)
			(size 1.016 1.27)
			(layers "B.Cu" "B.Mask" "B.Paste")
			(net "GND")
		)
	)
)
